# S9S_MB_2U (Grand Teton) — schematic netlist excerpt (pin names and nets, part order shuffled) for the footprints in the layout excerpt that follows; sources: Cadence DE-HDL packaged netlist, KiCad conversion of 03242023_DA0F0TMBIJ0_F0T_Motherboard_J_brd_V01_OCP.brd

R3107  Q_RES  0 5% CHIP  pkg 0402LF  page 234 : A = SMB_2_BMC_GPU_SCL ; B = SMB_2_BMC_GPU_R_SCL
R3521  Q_RES  54.9K 1% CHIP  pkg 0402LF  page 234 : A = P3V3_AUX ; B = SMB_2_BMC_GPU_BUF_R_SCL

(kicad_pcb
	(version 20260206)
	(generator "pcbnew")
	(generator_version "10.0")
	(general
		(thickness 1.6)
		(legacy_teardrops no)
	)
	(paper "A4")
	(title_block
		(title "03242023_DA0F0TMBIJ0_F0T_Motherboard_J_brd_V01_OCP.brd")
		(comment 1 "Grand Teton / footprints 2889-2890 of 6105")
	)
	(layers
		(0 "F.Cu" signal "TOP")
		(4 "In1.Cu" signal "GND")
		(6 "In2.Cu" signal "IN1")
		(8 "In3.Cu" signal "GND1")
		(10 "In4.Cu" signal "IN2")
		(12 "In5.Cu" signal "GND2")
		(14 "In6.Cu" signal "IN3")
		(16 "In7.Cu" signal "GND3")
		(18 "In8.Cu" signal "VCC")
		(20 "In9.Cu" signal "VCC1")
		(22 "In10.Cu" signal "GND4")
		(24 "In11.Cu" signal "IN4")
		(26 "In12.Cu" signal "GND5")
		(28 "In13.Cu" signal "IN5")
		(30 "In14.Cu" signal "GND6")
		(32 "In15.Cu" signal "IN6")
		(34 "In16.Cu" signal "GND7")
		(2 "B.Cu" signal "BOTTOM")
		(9 "F.Adhes" user "F.Adhesive")
		(11 "B.Adhes" user "B.Adhesive")
		(13 "F.Paste" user "Package Geometry/Pastemask Top")
		(15 "B.Paste" user "Package Geometry/Pastemask Bottom")
		(5 "F.SilkS" user "Ref Des/Silkscreen Top")
		(7 "B.SilkS" user "Ref Des/Silkscreen Bottom")
		(1 "F.Mask" user "Board Geometry/Soldermask Top")
		(3 "B.Mask" user "Board Geometry/Soldermask Bottom")
		(17 "Dwgs.User" user "User.Drawings")
		(19 "Cmts.User" user "User.Comments")
		(21 "Eco1.User" user "User.Eco1")
		(23 "Eco2.User" user "User.Eco2")
		(25 "Edge.Cuts" user "Board Geometry/Outline")
		(27 "Margin" user)
		(31 "F.CrtYd" user "Package Geometry/Place Bound Top")
		(29 "B.CrtYd" user "Package Geometry/Place Bound Bottom")
		(35 "F.Fab" user "Ref Des/Assembly Top")
		(33 "B.Fab" user "Ref Des/Assembly Bottom")
	)
	(footprint ""
		(layer "F.Cu")
		(at 46.626018 -440.205368 180)
		(property "Reference" "R3107"
			(at 0 0 180)
			(layer "F.SilkS")
			(hide yes)
			(effects
				(font
					(size 1.27 1.27)
				)
			)
		)
		(property "Value" ""
			(at 0 0 180)
			(layer "F.Fab")
			(effects
				(font
					(size 1.27 1.27)
				)
			)
		)
		(duplicate_pad_numbers_are_jumpers no)
		(fp_line
			(start 0.7874 0.4064)
			(end -0.7874 0.4064)
			(stroke
				(width 0.1524)
				(type default)
			)
			(layer "F.SilkS")
		)
		(fp_line
			(start 0.7874 -0.4064)
			(end 0.7874 0.4064)
			(stroke
				(width 0.1524)
				(type default)
			)
			(layer "F.SilkS")
		)
		(fp_line
			(start -0.7874 0.4064)
			(end -0.7874 -0.4064)
			(stroke
				(width 0.1524)
				(type default)
			)
			(layer "F.SilkS")
		)
		(fp_line
			(start -0.7874 -0.4064)
			(end 0.7874 -0.4064)
			(stroke
				(width 0.1524)
				(type default)
			)
			(layer "F.SilkS")
		)
		(fp_line
			(start 0.67945 0.3048)
			(end 0.120396 0.3048)
			(stroke
				(width 0.1)
				(type default)
			)
			(layer "F.Fab")
		)
		(fp_line
			(start 0.67945 -0.3048)
			(end 0.67945 0.3048)
			(stroke
				(width 0.1)
				(type default)
			)
			(layer "F.Fab")
		)
		(fp_line
			(start 0.12065 -0.2794)
			(end 0.12065 -0.3048)
			(stroke
				(width 0.1)
				(type default)
			)
			(layer "F.Fab")
		)
		(fp_line
			(start 0.12065 -0.3048)
			(end 0.67945 -0.3048)
			(stroke
				(width 0.1)
				(type default)
			)
			(layer "F.Fab")
		)
		(fp_line
			(start 0.120396 0.3048)
			(end 0.120396 0.2794)
			(stroke
				(width 0.1)
				(type default)
			)
			(layer "F.Fab")
		)
		(fp_line
			(start 0.120396 0.2794)
			(end -0.12065 0.2794)
			(stroke
				(width 0.1)
				(type default)
			)
			(layer "F.Fab")
		)
		(fp_line
			(start -0.12065 0.3048)
			(end -0.67945 0.3048)
			(stroke
				(width 0.1)
				(type default)
			)
			(layer "F.Fab")
		)
		(fp_line
			(start -0.12065 0.2794)
			(end -0.12065 0.3048)
			(stroke
				(width 0.1)
				(type default)
			)
			(layer "F.Fab")
		)
		(fp_line
			(start -0.12065 -0.2794)
			(end 0.12065 -0.2794)
			(stroke
				(width 0.1)
				(type default)
			)
			(layer "F.Fab")
		)
		(fp_line
			(start -0.12065 -0.305054)
			(end -0.12065 -0.2794)
			(stroke
				(width 0.1)
				(type default)
			)
			(layer "F.Fab")
		)
		(fp_line
			(start -0.67945 0.3048)
			(end -0.67945 -0.305054)
			(stroke
				(width 0.1)
				(type default)
			)
			(layer "F.Fab")
		)
		(fp_line
			(start -0.67945 -0.305054)
			(end -0.12065 -0.305054)
			(stroke
				(width 0.1)
				(type default)
			)
			(layer "F.Fab")
		)
		(pad "1" smd circle
			(at -0.40005 0 180)
			(size 0 0)
			(layers "F.Cu" "F.Mask" "F.Paste")
			(net "SMB_2_BMC_GPU_SCL")
		)
		(pad "2" smd circle
			(at 0.40005 0 180)
			(size 0 0)
			(layers "F.Cu" "F.Mask" "F.Paste")
			(net "SMB_2_BMC_GPU_R_SCL")
		)
	)
	(footprint ""
		(layer "F.Cu")
		(at 46.626018 -439.189368 180)
		(property "Reference" "R3521"
			(at 0 0 180)
			(layer "F.SilkS")
			(hide yes)
			(effects
				(font
					(size 1.27 1.27)
				)
			)
		)
		(property "Value" ""
			(at 0 0 180)
			(layer "F.Fab")
			(effects
				(font
					(size 1.27 1.27)
				)
			)
		)
		(duplicate_pad_numbers_are_jumpers no)
		(fp_line
			(start 0.7874 0.4064)
			(end -0.7874 0.4064)
			(stroke
				(width 0.1524)
				(type default)
			)
			(layer "F.SilkS")
		)
		(fp_line
			(start 0.7874 -0.4064)
			(end 0.7874 0.4064)
			(stroke
				(width 0.1524)
				(type default)
			)
			(layer "F.SilkS")
		)
		(fp_line
			(start -0.7874 0.4064)
			(end -0.7874 -0.4064)
			(stroke
				(width 0.1524)
				(type default)
			)
			(layer "F.SilkS")
		)
		(fp_line
			(start -0.7874 -0.4064)
			(end 0.7874 -0.4064)
			(stroke
				(width 0.1524)
				(type default)
			)
			(layer "F.SilkS")
		)
		(fp_line
			(start 0.67945 0.3048)
			(end 0.120396 0.3048)
			(stroke
				(width 0.1)
				(type default)
			)
			(layer "F.Fab")
		)
		(fp_line
			(start 0.67945 -0.3048)
			(end 0.67945 0.3048)
			(stroke
				(width 0.1)
				(type default)
			)
			(layer "F.Fab")
		)
		(fp_line
			(start 0.12065 -0.2794)
			(end 0.12065 -0.3048)
			(stroke
				(width 0.1)
				(type default)
			)
			(layer "F.Fab")
		)
		(fp_line
			(start 0.12065 -0.3048)
			(end 0.67945 -0.3048)
			(stroke
				(width 0.1)
				(type default)
			)
			(layer "F.Fab")
		)
		(fp_line
			(start 0.120396 0.3048)
			(end 0.120396 0.2794)
			(stroke
				(width 0.1)
				(type default)
			)
			(layer "F.Fab")
		)
		(fp_line
			(start 0.120396 0.2794)
			(end -0.12065 0.2794)
			(stroke
				(width 0.1)
				(type default)
			)
			(layer "F.Fab")
		)
		(fp_line
			(start -0.12065 0.3048)
			(end -0.67945 0.3048)
			(stroke
				(width 0.1)
				(type default)
			)
			(layer "F.Fab")
		)
		(fp_line
			(start -0.12065 0.2794)
			(end -0.12065 0.3048)
			(stroke
				(width 0.1)
				(type default)
			)
			(layer "F.Fab")
		)
		(fp_line
			(start -0.12065 -0.2794)
			(end 0.12065 -0.2794)
			(stroke
				(width 0.1)
				(type default)
			)
			(layer "F.Fab")
		)
		(fp_line
			(start -0.12065 -0.305054)
			(end -0.12065 -0.2794)
			(stroke
				(width 0.1)
				(type default)
			)
			(layer "F.Fab")
		)
		(fp_line
			(start -0.67945 0.3048)
			(end -0.67945 -0.305054)
			(stroke
				(width 0.1)
				(type default)
			)
			(layer "F.Fab")
		)
		(fp_line
			(start -0.67945 -0.305054)
			(end -0.12065 -0.305054)
			(stroke
				(width 0.1)
				(type default)
			)
			(layer "F.Fab")
		)
		(pad "1" smd circle
			(at -0.40005 0 180)
			(size 0 0)
			(layers "F.Cu" "F.Mask" "F.Paste")
			(net "P3V3_AUX")
		)
		(pad "2" smd circle
			(at 0.40005 0 180)
			(size 0 0)
			(layers "F.Cu" "F.Mask" "F.Paste")
			(net "SMB_2_BMC_GPU_BUF_R_SCL")
		)
	)
)
